FILE_TYPE = CONNECTIVITY;
{Allegro Design Entry HDL 16.6-p007 (v16-6-112F) 10/10/2012}
"PAGE_NUMBER" = 121;
0"NC";
1"GND\g";
2"P3V3_STBY\g";
3"GND\g";
4"RMII_SPRNGVLLE_BMC_PCH_RXD1_R1";
5"FM_CPU_ERR0_PCH_N";
6"H_CPU0_MEMABC_MEMHOT_PCH_N";
7"H_CPU1_MEMGHJ_MEMHOT_PCH_N";
8"A_1P8_3P3_RCOMP";
9"FM_OCP_MEZZC_PRES_N";
10"FM_CPU1_PROCHOT_PCH_N";
11"RMII_BMC_PCH_SPRNGVLLE_TXD0";
12"RMII_BMC_PCH_SPRNGVLLE_TXD1";
13"RMII_BMC_PCH_SPRNGVLLE_TXEN";
14"FM_PRSNT_2_5_N";
15"CLK_50M_CKMNG_PCH_10GBE";
16"FM_CPU_ERR1_PCH_N";
17"FM_CPU0_PROCHOT_PCH_N";
18"H_CPU1_MEMKLM_MEMHOT_PCH_N";
19"H_CPU0_MEMDEF_MEMHOT_PCH_N";
20"FM_INTRUDER_HDR_PCH_N";
21"RMII_BMC_PCH_SPRNGVLLE_CRSDV";
22"CLK_50M_CKMNG_PCH_10GBE";
23"RMII_BMC_PCH_SPRNGVLLE_CRSDV_R1";
24"RMII_BMC_PCH_SPRNGVLLE_CRSDV_R1";
25"RMII_SPRNGVLLE_BMC_PCH_RXD0";
26"RMII_SPRNGVLLE_BMC_PCH_RXD0_R1";
27"RMII_SPRNGVLLE_BMC_PCH_RXD0_R1";
28"RMII_BMC_PCH_SPRNGVLLE_RXER_R";
29"RMII_PCH_SPRNGVLLE_ARB_IN";
30"RMII_PCH_SPRNGVLLE_ARB_OUT_R";
31"FM_PRSNT_2_1_N";
32"RMII_SPRNGVLLE_BMC_PCH_RXD1";
33"RMII_SPRNGVLLE_BMC_PCH_RXD1_R1";
34"TP_PCH_RSVD16";
35"RMII_BMC_PCH_SPRNGVLLE_RXER";
36"RMII_BMC_PCH_SPRNGVLLE_RXER_R";
37"RST_PCIE_PCH_PERST_N";
38"RMII_PCH_SPRNGVLLE_ARB_OUT";
39"RMII_PCH_SPRNGVLLE_ARB_OUT_R";
40"FM_PRSNT_2_4_N";
41"TP_PCH_RSVD14";
42"TP_PCH_RSVD13";
43"SPI_PCH_MOSI_R";
44"SPI_PCH_IO3";
45"SPI_PCH_TPM_CS_N";
46"TP_PCH_DISPA_BCLK";
47"TP_PCH_RSVD4";
48"SPI_PCH_IO2";
49"FM_PCH_PRSNT_N";
50"FM_PRSNT_2_3_N";
51"FM_OCP_MEZZB_PRES_N";
52"TP_PCH_GPP_L10";
53"TP_PCH_RSVD15";
54"TP_PCH_RSVD17";
55"TP_PCH_RSVD18";
56"FM_PRSNT_2_6_N";
57"TP_PCH_RSVD19";
58"TP_PCH_RSVD22";
59"FM_PRSNT_2_2_N";
60"TP_PCH_GPP_L11";
61"TP_PCH_RSVD20";
62"TP_PCH_RSVD21";
63"TP_PCH_RSVD23";
64"TP_PCH_RSVD24";
65"TP_PCH_RSVD25";
66"TP_PCH_RSVD0";
67"TP_PCH_RSVD1";
68"TP_PCH_RSVD2";
69"TP_PCH_RSVD3";
70"TP_PCH_RSVD5";
71"TP_PCH_RSVD6";
72"TP_PCH_RSVD7";
73"TP_PCH_RSVD8";
74"TP_PCH_RSVD9";
75"TP_PCH_RSVD12";
76"TP_PCH_DISPA_SDI";
77"TP_PCH_DISPA_SDO";
78"TP_PCH_HDA_SYNC";
79"TP_PCH_HDA_SDI_1";
80"TP_PCH_HDA_SDI_0";
81"TP_PCH_HSA_RST_N";
82"TP_PCH_HDA_BCLK";
83"TP_SPI_PCH_CS1_R1_N";
84"SPI_PCH_CS0_R_N";
85"TP_PCH_RSVD26";
86"TP_PCH_RSVD27";
87"TP_PCH_RSVD46";
88"RST_RTCRST_N";
89"SPI_PCH_CLK";
90"FM_FLASH_DESC_OVERRIDE";
91"FM_SINT_PRSNT_N";
92"FM_WBG_PRSNT_N";
93"SPI_PCH_MISO";
94"RST_SRTCRST_N";
95"SPI_PCH_MOSI";
96"SPI_PCH_CS0_N";
%"RES"
"1","(-5100,1175)","0","mstr_discrete","I101";
;
CDS_SEC"1"
CDS_LOCATION"R8D11"
SEC"1"
SEC_TYPE"0402"
CDS_LIB"mstr_discrete"
ROOM"SB"
WATTAGE"1/16W"
PART_NUMBER"G21796-074"
MATERIAL"CHIP"
PACK_TYPE"0402"
TOLERANCE"1%"
VALUE"33.2"
LOCATION"R8D11";
"B"
$PN"2"39;
"A"
$PN"1"38;
%"RES"
"1","(-1925,3150)","0","mstr_discrete","I31";
;
CDS_LOCATION"R7C15"
$SEC"1"
CDS_SEC"1"
CDS_LIB"mstr_discrete"
ROOM"SB"
WATTAGE"1/16W"
MATERIAL"CHIP"
PACK_TYPE"0402"
TOLERANCE"5%"
VALUE"0.0"
PART_NUMBER"G21497-005"
LOCATION"R7C15";
"B"
$PN"2"95;
"A"
$PN"1"43;
%"RES"
"1","(-1950,3550)","0","mstr_discrete","I33";
;
CDS_LOCATION"R7C16"
$SEC"1"
CDS_SEC"1"
CDS_LIB"mstr_discrete"
ROOM"SB"
PACK_TYPE"0402"
PART_NUMBER"G21796-074"
WATTAGE"1/16W"
MATERIAL"CHIP"
TOLERANCE"1%"
VALUE"33.2"
LOCATION"R7C16";
"B"
$PN"2"96;
"A"
$PN"1"84;
%"LBG_CORE_QAT_EXT_D"
"8","(-4050,2800)","0","mstr_u_proc","I34";
;
CDS_SEC"8"
SEC_TYPE"BGA1"
SEC"8"
CDS_LIB"mstr_u_proc"
BOM_COST"SB"
CDS_LOCATION"U7C1"
ROOM"SB"
PACK_TYPE"BGA1"
MATERIAL"IC"
PART_NUMBER"H91415-002"
LOCATION"U7C1";
"CGC_DUT_DETECT_N"
$PN"C70"49;
"GPIO_RCOMP_1P8_3P3"
$PN"AM4"8;
"GPP_K0_LAN_NCSI_CLK_IN"
$PN"AJ1"15;
"GPP_K10_PE_RST_N"
$PN"AH4"37;
"GPP_K1_LAN_NCSI_TXD0"
$PN"AM2"11;
"GPP_K2_LAN_NCSI_TXD1"
$PN"AK2"12;
"GPP_K3_LAN_NCSI_TX_EN"
$PN"AL3"13;
"GPP_K4_LAN_NCSI_CRS_DV"
$PN"AN3"24;
"GPP_K5_LAN_NCSI_RXD0"
$PN"AL1"27;
"GPP_K6_LAN_NCSI_RXD1"
$PN"AN1"4;
"GPP_K7"
$PN"AH2"28;
"GPP_K8_LAN_NCSI_ARB_IN"
$PN"AJ3"29;
"GPP_K9_LAN_NCSI_ARB_OUT"
$PN"AK4"30;
"GPP_L10_TESTCH0_CLK"
$PN"AF20"52;
"GPP_L11_TESTCH1_D0"
$PN"AD20"60;
"GPP_L12_TESTCH1_D1"
$PN"Y15"6;
"GPP_L13_TESTCH1_D2"
$PN"AD13"19;
"GPP_L14_TESTCH1_D3"
$PN"AA13"7;
"GPP_L15_TESTCH1_D4"
$PN"Y11"18;
"GPP_L16_TESTCH1_D5"
$PN"Y7"17;
"GPP_L17_TESTCH1_D6"
$PN"AA9"10;
"GPP_L18_TESTCH1_D7"
$PN"AE7"5;
"GPP_L19_TESTCH1_CLK"
$PN"AG11"16;
"GPP_L2_TESTCH0_D0"
$PN"AE18"31;
"GPP_L3_TESTCH0_D1"
$PN"AE15"59;
"GPP_L4_TESTCH0_D2"
$PN"AE11"50;
"GPP_L5_TESTCH0_D3"
$PN"Y18"40;
"GPP_L6_TESTCH0_D4"
$PN"AA20"14;
"GPP_L7_TESTCH0_D5"
$PN"AA17"56;
"GPP_L8_TESTCH0_D6"
$PN"AD9"51;
"GPP_L9_TESTCH0_D7"
$PN"AD17"9;
"HDA_BCLK"
$PN"P18"82;
"HDA_RST_N"
$PN"M18"81;
"HDA_SDI_0"
$PN"K20"80;
"HDA_SDI_1"
$PN"V18"79;
"HDA_SDO"
$PN"U24"90;
"HDA_SYNC"
$PN"H20"78;
"INTRUDER_N"
$PN"AG18"20;
"RSVD<68>"
$PN"V22"77;
"RSVD<67>"
$PN"R20"76;
"RSVD<66>"
$PN"U20"46;
"RSVD<46>"
$PN"BW3"87;
"RSVD<27>"
$PN"BG26"86;
"RSVD<26>"
$PN"BH24"85;
"RSVD<25>"
$PN"P48"65;
"RSVD<24>"
$PN"P44"64;
"RSVD<23>"
$PN"P40"63;
"RSVD<22>"
$PN"AT71"58;
"RSVD<21>"
$PN"A11"62;
"RSVD<20>"
$PN"D10"61;
"RSVD<19>"
$PN"C9"57;
"RSVD<18>"
$PN"C11"55;
"RSVD<17>"
$PN"B10"54;
"RSVD<16>"
$PN"C5"34;
"RSVD<15>"
$PN"C6"53;
"RSVD<14>"
$PN"E18"41;
"RSVD<13>"
$PN"C67"42;
"RSVD<12>"
$PN"C68"75;
"RSVD<11>"
$PN"C18"91;
"RSVD<10>"
$PN"D8"92;
"RSVD<9>"
$PN"F66"74;
"RSVD<8>"
$PN"F69"73;
"RSVD<7>"
$PN"F8"72;
"RSVD<6>"
$PN"AT69"71;
"RSVD<5>"
$PN"AG15"70;
"RSVD<4>"
$PN"P37"47;
"RSVD<3>"
$PN"V11"69;
"RSVD<2>"
$PN"AA58"68;
"RSVD<1>"
$PN"AC56"67;
"RSVD<0>"
$PN"AF61"66;
"RTCRST_N"
$PN"P11"88;
"SPI0_CLK"
$PN"K2"89;
"SPI0_FLASH_CS0_N"
$PN"J3"84;
"SPI0_FLASH_CS1_N"
$PN"G7"83;
"SPI0_IO2"
$PN"F5"48;
"SPI0_IO3"
$PN"L1"44;
"SPI0_MISO_IO1"
$PN"L3"93;
"SPI0_MOSI_IO0"
$PN"H4"43;
"SPI0_TPM_CS_N"
$PN"K4"45;
"SRTCRST_N"
$PN"G18"94;
%"RES"
"2","(-7750,3675)","0","mstr_discrete","I35";
;
CDS_SEC"1"
CDS_LIB"mstr_discrete"
SEC"1"
SEC_TYPE"0402"
ROOM"SB"
CDS_LOCATION"R8C26"
LOCATION"R8C26"
MATERIAL"CHIP"
WATTAGE"1/16W"
PART_NUMBER"G21796-017"
PACK_TYPE"0402"
TOLERANCE"1%"
VALUE"100.0";
"A"
$PN"1"8;
"B"
$PN"2"1;
%"RES"
"2","(-8075,2525)","0","mstr_discrete","I37";
;
CDS_SEC"1"
CDS_LOCATION"R3N10"
SEC"1"
SEC_TYPE"0402"
CDS_LIB"mstr_discrete"
ROOM"SB"
PART_NUMBER"G21796-016"
PACK_TYPE"0402"
WATTAGE"1/16W"
MATERIAL"CHIP"
TOLERANCE"1%"
VALUE"10.0K"
LOCATION"R3N10";
"A"
$PN"1"2;
"B"
$PN"2"20;
%"GND"
"1","(-7750,3450)","0","mstr_symbols","I39";
;
BODY_TYPE"PLUMBING"
CDS_LIB"mstr_symbols"
SIZE"1B"
HDL_POWER"GND"
VOLTAGE"0.0V";
"A\NAC"1;
%"P3V3_STBY"
"1","(-8075,2750)","0","mstr_symbols","I40";
;
CDS_LIB"mstr_symbols"
SIZE"1B"
BODY_TYPE"PLUMBING"
HDL_POWER"P3V3_STBY"
VOLTAGE"3.3V";
"G\NAC"2;
%"RES"
"2","(-8125,950)","0","mstr_discrete","I73";
;
CDS_SEC"1"
CDS_LIB"mstr_discrete"
SEC_TYPE"0402"
BOM_COST"NT_GBE_BASE"
SEC"1"
CDS_LOCATION"R7C20"
ROOM"NIC_SPRV"
LOCATION"R7C20"
WATTAGE"1/16W"
MATERIAL"CHIP"
PACK_TYPE"0402"
TOLERANCE"1%"
VALUE"10.0K"
PART_NUMBER"G21796-016";
"A"
$PN"1"22;
"B"
$PN"2"3;
%"GND"
"1","(-8125,675)","0","mstr_symbols","I74";
;
BODY_TYPE"PLUMBING"
CDS_LIB"mstr_symbols"
SIZE"1B"
HDL_POWER"GND"
VOLTAGE"0.0V";
"A\NAC"3;
%"RES"
"1","(-5100,550)","0","mstr_discrete","I89";
;
SEC_TYPE"0402"
CDS_LIB"mstr_discrete"
SEC"1"
CDS_LOCATION"R3P3"
CDS_SEC"1"
WATTAGE"1/16W"
PART_NUMBER"G21497-005"
MATERIAL"CHIP"
PACK_TYPE"0402"
TOLERANCE"5%"
VALUE"0.0"
LOCATION"R3P3";
"B"
$PN"2"26;
"A"
$PN"1"25;
%"RES"
"1","(-5100,850)","0","mstr_discrete","I90";
;
CDS_SEC"1"
CDS_LOCATION"R3P2"
SEC"1"
CDS_LIB"mstr_discrete"
SEC_TYPE"0402"
WATTAGE"1/16W"
PART_NUMBER"G21497-005"
LOCATION"R3P2"
MATERIAL"CHIP"
PACK_TYPE"0402"
TOLERANCE"5%"
VALUE"0.0";
"B"
$PN"2"23;
"A"
$PN"1"21;
%"RES"
"1","(-5100,700)","0","mstr_discrete","I91";
;
SEC_TYPE"0402"
CDS_LIB"mstr_discrete"
SEC"1"
CDS_LOCATION"R2P1"
CDS_SEC"1"
WATTAGE"1/16W"
PACK_TYPE"0402"
MATERIAL"CHIP"
TOLERANCE"5%"
VALUE"0.0"
PART_NUMBER"G21497-005"
LOCATION"R2P1";
"B"
$PN"2"33;
"A"
$PN"1"32;
%"RES"
"1","(-5100,1025)","0","mstr_discrete","I98";
;
CDS_SEC"1"
CDS_LOCATION"R7C14"
SEC"1"
SEC_TYPE"0402"
CDS_LIB"mstr_discrete"
ROOM"SB"
WATTAGE"1/16W"
PART_NUMBER"G21796-074"
LOCATION"R7C14"
MATERIAL"CHIP"
PACK_TYPE"0402"
TOLERANCE"1%"
VALUE"33.2";
"B"
$PN"2"36;
"A"
$PN"1"35;
END.
